# Stackup_F0T_Fan_BP_6L_1p6mm_IT-170GT_RTF_Rev0p1_20211021.xls — Manufacuring violation (pcb-stackup)
| Description | Quanta layout design rule | The stackup design rule |  |
| Min. Innerlayer Line Width, 0.5 oz copper (mil) | 3 | NA | Normal |
| Min. Innerlayer Space, 0.5 oz copper (mil) | 3.5 | NA | Medium |
| Min. Innerlayer Line Width,   1 oz copper (mil) | 4 | 4 | High |
| Min. Innerlayer Space, 1 oz copper (mil) | 4 | NA |  |
| Min. Innerlayer Line Width,   2oz copper (mil) | 6 | NA |  |
| Min. Innerlayer Space,  2oz copper (mil) | 6 | NA |  |
| Min. Outerlayer line width, 0.5oz copper foil (mil) | 3.5 | 4 |  |
| Min. Outerlayer Space, 0.5oz copper foil (mil) | 3.5 | NA |  |
| Min. Inner Core/PP thickness (mil) | 3 | 6 |  |
| Max. Aspect Ratio for min. DHS | 12.24 | 6.43 |  |
